# T6G (Grand Teton) — schematic netlist excerpt (pin names and nets, part order shuffled) for the footprints in the layout excerpt that follows; sources: Cadence DE-HDL packaged netlist, KiCad conversion of 04192023_DAF0TMB3IC0_F0TG_MB_C_brd_V02_OCP.brd

R6137  Q_RES  1K 1% EMPTY  pkg 0402LF  page 84 : A = P3V3_AUX ; B = FM_BOARD_BMC_SKU_ID3

PU55  MPQ8633AGLEC807Z  MPQ8633AGLE-C807-Z IC  pkg QFN14_4X3  page 192
  BST  = SW_PVDD_33_S5_BST
  AGND  = GND
  CS  = PVDD_33_S5_CS
  MODE  = PVDD_33_S5_MODE
  TRK_REF  = PVDD_33_S5_REF
  RGND  = GND
  FB  = PVDD_33_S5_FB
  EN  = PVDD33_S5_EN
  PGOOD  = PWRGD_PVDD33_S5
  VIN1  = SW_P12V_AUX_PVDD_33_S5_FLT
  PGND  = GND
  VCC  = PVDD_33_S5_VCC
  SW  = SW_PVDD_33_S5_SW
  VIN2  = SW_P12V_AUX_PVDD_33_S5_FLT

(kicad_pcb
	(version 20260206)
	(generator "pcbnew")
	(generator_version "10.0")
	(general
		(thickness 1.6)
		(legacy_teardrops no)
	)
	(paper "A4")
	(title_block
		(title "04192023_DAF0TMB3IC0_F0TG_MB_C_brd_V02_OCP.brd")
		(comment 1 "Grand Teton / footprints 2122-2123 of 8354")
	)
	(layers
		(0 "F.Cu" signal "TOP")
		(4 "In1.Cu" signal "GND")
		(6 "In2.Cu" signal "IN1")
		(8 "In3.Cu" signal "GND1")
		(10 "In4.Cu" signal "IN2")
		(12 "In5.Cu" signal "GND2")
		(14 "In6.Cu" signal "IN3")
		(16 "In7.Cu" signal "GND3")
		(18 "In8.Cu" signal "VCC")
		(20 "In9.Cu" signal "VCC1")
		(22 "In10.Cu" signal "GND4")
		(24 "In11.Cu" signal "IN4")
		(26 "In12.Cu" signal "GND5")
		(28 "In13.Cu" signal "IN5")
		(30 "In14.Cu" signal "GND6")
		(32 "In15.Cu" signal "IN6")
		(34 "In16.Cu" signal "GND7")
		(2 "B.Cu" signal "BOTTOM")
		(9 "F.Adhes" user "F.Adhesive")
		(11 "B.Adhes" user "B.Adhesive")
		(13 "F.Paste" user "Package Geometry/Pastemask Top")
		(15 "B.Paste" user "Package Geometry/Pastemask Bottom")
		(5 "F.SilkS" user "Ref Des/Silkscreen Top")
		(7 "B.SilkS" user "Ref Des/Silkscreen Bottom")
		(1 "F.Mask" user "Board Geometry/Soldermask Top")
		(3 "B.Mask" user "Board Geometry/Soldermask Bottom")
		(17 "Dwgs.User" user "User.Drawings")
		(19 "Cmts.User" user "User.Comments")
		(21 "Eco1.User" user "User.Eco1")
		(23 "Eco2.User" user "User.Eco2")
		(25 "Edge.Cuts" user "Board Geometry/Outline")
		(27 "Margin" user)
		(31 "F.CrtYd" user "Package Geometry/Place Bound Top")
		(29 "B.CrtYd" user "Package Geometry/Place Bound Bottom")
		(35 "F.Fab" user "Ref Des/Assembly Top")
		(33 "B.Fab" user "Ref Des/Assembly Bottom")
	)
	(footprint ""
		(layer "F.Cu")
		(at 167.11676 -117.301772)
		(property "Reference" "R6137"
			(at 0 0 0)
			(layer "F.SilkS")
			(hide yes)
			(effects
				(font
					(size 1.27 1.27)
				)
			)
		)
		(property "Value" ""
			(at 0 0 0)
			(layer "F.Fab")
			(effects
				(font
					(size 1.27 1.27)
				)
			)
		)
		(duplicate_pad_numbers_are_jumpers no)
		(fp_line
			(start -0.7874 -0.4064)
			(end 0.7874 -0.4064)
			(stroke
				(width 0.1524)
				(type default)
			)
			(layer "F.SilkS")
		)
		(fp_line
			(start -0.7874 0.4064)
			(end -0.7874 -0.4064)
			(stroke
				(width 0.1524)
				(type default)
			)
			(layer "F.SilkS")
		)
		(fp_line
			(start 0.7874 -0.4064)
			(end 0.7874 0.4064)
			(stroke
				(width 0.1524)
				(type default)
			)
			(layer "F.SilkS")
		)
		(fp_line
			(start 0.7874 0.4064)
			(end -0.7874 0.4064)
			(stroke
				(width 0.1524)
				(type default)
			)
			(layer "F.SilkS")
		)
		(fp_line
			(start -0.67945 -0.305054)
			(end -0.12065 -0.305054)
			(stroke
				(width 0.1)
				(type default)
			)
			(layer "F.Fab")
		)
		(fp_line
			(start -0.67945 0.3048)
			(end -0.67945 -0.305054)
			(stroke
				(width 0.1)
				(type default)
			)
			(layer "F.Fab")
		)
		(fp_line
			(start -0.12065 -0.305054)
			(end -0.12065 -0.2794)
			(stroke
				(width 0.1)
				(type default)
			)
			(layer "F.Fab")
		)
		(fp_line
			(start -0.12065 -0.2794)
			(end 0.12065 -0.2794)
			(stroke
				(width 0.1)
				(type default)
			)
			(layer "F.Fab")
		)
		(fp_line
			(start -0.12065 0.2794)
			(end -0.12065 0.3048)
			(stroke
				(width 0.1)
				(type default)
			)
			(layer "F.Fab")
		)
		(fp_line
			(start -0.12065 0.3048)
			(end -0.67945 0.3048)
			(stroke
				(width 0.1)
				(type default)
			)
			(layer "F.Fab")
		)
		(fp_line
			(start 0.120396 0.2794)
			(end -0.12065 0.2794)
			(stroke
				(width 0.1)
				(type default)
			)
			(layer "F.Fab")
		)
		(fp_line
			(start 0.120396 0.3048)
			(end 0.120396 0.2794)
			(stroke
				(width 0.1)
				(type default)
			)
			(layer "F.Fab")
		)
		(fp_line
			(start 0.12065 -0.3048)
			(end 0.67945 -0.3048)
			(stroke
				(width 0.1)
				(type default)
			)
			(layer "F.Fab")
		)
		(fp_line
			(start 0.12065 -0.2794)
			(end 0.12065 -0.3048)
			(stroke
				(width 0.1)
				(type default)
			)
			(layer "F.Fab")
		)
		(fp_line
			(start 0.67945 -0.3048)
			(end 0.67945 0.3048)
			(stroke
				(width 0.1)
				(type default)
			)
			(layer "F.Fab")
		)
		(fp_line
			(start 0.67945 0.3048)
			(end 0.120396 0.3048)
			(stroke
				(width 0.1)
				(type default)
			)
			(layer "F.Fab")
		)
		(pad "1" smd circle
			(at -0.40005 0)
			(size 0 0)
			(layers "F.Cu" "F.Mask" "F.Paste")
			(net "P3V3_AUX")
		)
		(pad "2" smd circle
			(at 0.40005 0)
			(size 0 0)
			(layers "F.Cu" "F.Mask" "F.Paste")
			(net "FM_BOARD_BMC_SKU_ID3")
		)
	)
	(footprint ""
		(layer "F.Cu")
		(at 200.854056 -340.655148 180)
		(property "Reference" "PU55"
			(at -5.548884 -2.521712 90)
			(unlocked yes)
			(layer "F.SilkS")
			(effects
				(font
					(size 0.7874 0.5842)
					(thickness 0.1524)
				)
				(justify left)
			)
		)
		(property "Value" ""
			(at 0 0 180)
			(layer "F.Fab")
			(effects
				(font
					(size 1.27 1.27)
				)
			)
		)
		(duplicate_pad_numbers_are_jumpers no)
		(fp_line
			(start 1.549908 -1.9812)
			(end 1.549908 -2.050034)
			(stroke
				(width 0.1524)
				(type default)
			)
			(layer "F.SilkS")
		)
		(fp_line
			(start 1.549908 -2.050034)
			(end 0.5842 -2.050034)
			(stroke
				(width 0.1524)
				(type default)
			)
			(layer "F.SilkS")
		)
		(fp_line
			(start 0 2.050034)
			(end 1.549908 2.050034)
			(stroke
				(width 0.1524)
				(type default)
			)
			(layer "F.SilkS")
		)
		(fp_line
			(start -0.5842 -2.050034)
			(end -1.549908 -2.050034)
			(stroke
				(width 0.1524)
				(type default)
			)
			(layer "F.SilkS")
		)
		(fp_line
			(start -1.549908 2.050034)
			(end -0.5842 2.050034)
			(stroke
				(width 0.1524)
				(type default)
			)
			(layer "F.SilkS")
		)
		(fp_line
			(start -1.549908 1.9812)
			(end -1.549908 2.050034)
			(stroke
				(width 0.1524)
				(type default)
			)
			(layer "F.SilkS")
		)
		(fp_line
			(start -1.549908 -2.050034)
			(end -1.549908 -1.9812)
			(stroke
				(width 0.1524)
				(type default)
			)
			(layer "F.SilkS")
		)
		(fp_poly
			(pts
				(xy -1.9304 -1.700022) (xy -2.641854 -1.344168) (xy -2.641854 -2.055876)
			)
			(stroke
				(width 0)
				(type default)
			)
			(fill yes)
			(layer "F.SilkS")
		)
		(fp_line
			(start 1.549908 2.050034)
			(end 1.549908 -2.050034)
			(stroke
				(width 0.1)
				(type default)
			)
			(layer "F.Fab")
		)
		(fp_line
			(start 1.549908 -2.050034)
			(end -1.549908 -2.050034)
			(stroke
				(width 0.1)
				(type default)
			)
			(layer "F.Fab")
		)
		(fp_line
			(start -1.549908 2.050034)
			(end 1.549908 2.050034)
			(stroke
				(width 0.1)
				(type default)
			)
			(layer "F.Fab")
		)
		(fp_line
			(start -1.549908 -2.050034)
			(end -1.549908 2.050034)
			(stroke
				(width 0.1)
				(type default)
			)
			(layer "F.Fab")
		)
		(fp_poly
			(pts
				(xy -2.9464 -2.208022) (xy -2.9464 -1.192022) (xy -1.9304 -1.700022)
			)
			(stroke
				(width 0)
				(type default)
			)
			(fill yes)
			(layer "F.Fab")
		)
		(pad "1" smd circle
			(at -1.35001 -1.700022 180)
			(size 0 0)
			(layers "F.Cu" "F.Mask" "F.Paste")
			(net "SW_PVDD_33_S5_BST")
		)
		(pad "2" smd rect
			(at -1.400048 -1.199896 270)
			(size 0.1778 0.8128)
			(layers "F.Cu" "F.Mask" "F.Paste")
			(net "GND")
		)
		(pad "3" smd rect
			(at -1.400048 -0.8001 270)
			(size 0.1778 0.8128)
			(layers "F.Cu" "F.Mask" "F.Paste")
			(net "PVDD_33_S5_CS")
		)
		(pad "4" smd rect
			(at -1.400048 -0.40005 270)
			(size 0.1778 0.8128)
			(layers "F.Cu" "F.Mask" "F.Paste")
			(net "PVDD_33_S5_MODE")
		)
		(pad "5" smd rect
			(at -1.400048 0 270)
			(size 0.1778 0.8128)
			(layers "F.Cu" "F.Mask" "F.Paste")
			(net "PVDD_33_S5_REF")
		)
		(pad "6" smd rect
			(at -1.400048 0.40005 270)
			(size 0.1778 0.8128)
			(layers "F.Cu" "F.Mask" "F.Paste")
			(net "GND")
		)
		(pad "7" smd rect
			(at -1.400048 0.8001 270)
			(size 0.1778 0.8128)
			(layers "F.Cu" "F.Mask" "F.Paste")
			(net "PVDD_33_S5_FB")
		)
		(pad "8" smd rect
			(at -1.400048 1.199896 270)
			(size 0.1778 0.8128)
			(layers "F.Cu" "F.Mask" "F.Paste")
			(net "PVDD33_S5_EN")
		)
		(pad "9" smd rect
			(at -1.400048 1.700022 270)
			(size 0.3048 0.8128)
			(layers "F.Cu" "F.Mask" "F.Paste")
			(net "PWRGD_PVDD33_S5")
		)
		(pad "10" smd rect
			(at -0.299974 1.299972 180)
			(size 0.3048 2.0066)
			(layers "F.Cu" "F.Mask" "F.Paste")
			(net "SW_P12V_AUX_PVDD_33_S5_FLT")
		)
		(pad "11_18" smd circle
			(at 1.175004 0.275082 180)
			(size 0 0)
			(layers "F.Cu" "F.Mask" "F.Paste")
			(net "GND")
		)
		(pad "19" smd rect
			(at 1.400048 -1.700022 90)
			(size 0.3048 0.8128)
			(layers "F.Cu" "F.Mask" "F.Paste")
			(net "PVDD_33_S5_VCC")
		)
		(pad "20" smd rect
			(at 0.299974 -1.299972 180)
			(size 0.3048 2.0066)
			(layers "F.Cu" "F.Mask" "F.Paste")
			(net "SW_PVDD_33_S5_SW")
		)
		(pad "21" smd rect
			(at -0.299974 -1.299972 180)
			(size 0.3048 2.0066)
			(layers "F.Cu" "F.Mask" "F.Paste")
			(net "SW_P12V_AUX_PVDD_33_S5_FLT")
		)
	)
)
